# T6G (Grand Teton) — schematic netlist excerpt (pin names and nets, part order shuffled) for the footprints in the layout excerpt that follows; sources: Cadence DE-HDL packaged netlist, KiCad conversion of 04192023_DAF0TMB3IC0_F0TG_MB_C_brd_V02_OCP.brd

R277  Q_RES  33 5% CHIP  pkg 0402LF  page 81 : A = FM_CPU1_NMI_SYNC_FLOOD_N ; B = CPU1_NMI_SYNC_FLOOD_N
R6721  Q_RES  10K 1% CHIP  pkg 0201LF  page 320 : A = RST_RT_CPU1_P0_RESET_R_N ; B = GND
R72  Q_RES  22 1% CHIP  pkg 0402LF  page 132 : A = NCSI_BMC_RXD0_R ; B = RMII_OCP_BMC_RXD_0

(kicad_pcb
	(version 20260206)
	(generator "pcbnew")
	(generator_version "10.0")
	(general
		(thickness 1.6)
		(legacy_teardrops no)
	)
	(paper "A4")
	(title_block
		(title "04192023_DAF0TMB3IC0_F0TG_MB_C_brd_V02_OCP.brd")
		(comment 1 "Grand Teton / footprints 4280-4282 of 8354")
	)
	(layers
		(0 "F.Cu" signal "TOP")
		(4 "In1.Cu" signal "GND")
		(6 "In2.Cu" signal "IN1")
		(8 "In3.Cu" signal "GND1")
		(10 "In4.Cu" signal "IN2")
		(12 "In5.Cu" signal "GND2")
		(14 "In6.Cu" signal "IN3")
		(16 "In7.Cu" signal "GND3")
		(18 "In8.Cu" signal "VCC")
		(20 "In9.Cu" signal "VCC1")
		(22 "In10.Cu" signal "GND4")
		(24 "In11.Cu" signal "IN4")
		(26 "In12.Cu" signal "GND5")
		(28 "In13.Cu" signal "IN5")
		(30 "In14.Cu" signal "GND6")
		(32 "In15.Cu" signal "IN6")
		(34 "In16.Cu" signal "GND7")
		(2 "B.Cu" signal "BOTTOM")
		(9 "F.Adhes" user "F.Adhesive")
		(11 "B.Adhes" user "B.Adhesive")
		(13 "F.Paste" user "Package Geometry/Pastemask Top")
		(15 "B.Paste" user "Package Geometry/Pastemask Bottom")
		(5 "F.SilkS" user "Ref Des/Silkscreen Top")
		(7 "B.SilkS" user "Ref Des/Silkscreen Bottom")
		(1 "F.Mask" user "Board Geometry/Soldermask Top")
		(3 "B.Mask" user "Board Geometry/Soldermask Bottom")
		(17 "Dwgs.User" user "User.Drawings")
		(19 "Cmts.User" user "User.Comments")
		(21 "Eco1.User" user "User.Eco1")
		(23 "Eco2.User" user "User.Eco2")
		(25 "Edge.Cuts" user "Board Geometry/Outline")
		(27 "Margin" user)
		(31 "F.CrtYd" user "Package Geometry/Place Bound Top")
		(29 "B.CrtYd" user "Package Geometry/Place Bound Bottom")
		(35 "F.Fab" user "Ref Des/Assembly Top")
		(33 "B.Fab" user "Ref Des/Assembly Bottom")
	)
	(footprint ""
		(layer "F.Cu")
		(at 192.151 -129.377948 90)
		(property "Reference" "R277"
			(at 0 0 90)
			(layer "F.SilkS")
			(hide yes)
			(effects
				(font
					(size 1.27 1.27)
				)
			)
		)
		(property "Value" ""
			(at 0 0 90)
			(layer "F.Fab")
			(effects
				(font
					(size 1.27 1.27)
				)
			)
		)
		(duplicate_pad_numbers_are_jumpers no)
		(fp_line
			(start 0.7874 -0.4064)
			(end 0.7874 0.4064)
			(stroke
				(width 0.1524)
				(type default)
			)
			(layer "F.SilkS")
		)
		(fp_line
			(start -0.7874 -0.4064)
			(end 0.7874 -0.4064)
			(stroke
				(width 0.1524)
				(type default)
			)
			(layer "F.SilkS")
		)
		(fp_line
			(start 0.7874 0.4064)
			(end -0.7874 0.4064)
			(stroke
				(width 0.1524)
				(type default)
			)
			(layer "F.SilkS")
		)
		(fp_line
			(start -0.7874 0.4064)
			(end -0.7874 -0.4064)
			(stroke
				(width 0.1524)
				(type default)
			)
			(layer "F.SilkS")
		)
		(fp_line
			(start -0.12065 -0.305054)
			(end -0.12065 -0.2794)
			(stroke
				(width 0.1)
				(type default)
			)
			(layer "F.Fab")
		)
		(fp_line
			(start -0.67945 -0.305054)
			(end -0.12065 -0.305054)
			(stroke
				(width 0.1)
				(type default)
			)
			(layer "F.Fab")
		)
		(fp_line
			(start 0.67945 -0.3048)
			(end 0.67945 0.3048)
			(stroke
				(width 0.1)
				(type default)
			)
			(layer "F.Fab")
		)
		(fp_line
			(start 0.12065 -0.3048)
			(end 0.67945 -0.3048)
			(stroke
				(width 0.1)
				(type default)
			)
			(layer "F.Fab")
		)
		(fp_line
			(start 0.12065 -0.2794)
			(end 0.12065 -0.3048)
			(stroke
				(width 0.1)
				(type default)
			)
			(layer "F.Fab")
		)
		(fp_line
			(start -0.12065 -0.2794)
			(end 0.12065 -0.2794)
			(stroke
				(width 0.1)
				(type default)
			)
			(layer "F.Fab")
		)
		(fp_line
			(start 0.120396 0.2794)
			(end -0.12065 0.2794)
			(stroke
				(width 0.1)
				(type default)
			)
			(layer "F.Fab")
		)
		(fp_line
			(start -0.12065 0.2794)
			(end -0.12065 0.3048)
			(stroke
				(width 0.1)
				(type default)
			)
			(layer "F.Fab")
		)
		(fp_line
			(start 0.67945 0.3048)
			(end 0.120396 0.3048)
			(stroke
				(width 0.1)
				(type default)
			)
			(layer "F.Fab")
		)
		(fp_line
			(start 0.120396 0.3048)
			(end 0.120396 0.2794)
			(stroke
				(width 0.1)
				(type default)
			)
			(layer "F.Fab")
		)
		(fp_line
			(start -0.12065 0.3048)
			(end -0.67945 0.3048)
			(stroke
				(width 0.1)
				(type default)
			)
			(layer "F.Fab")
		)
		(fp_line
			(start -0.67945 0.3048)
			(end -0.67945 -0.305054)
			(stroke
				(width 0.1)
				(type default)
			)
			(layer "F.Fab")
		)
		(pad "1" smd circle
			(at -0.40005 0 90)
			(size 0 0)
			(layers "F.Cu" "F.Mask" "F.Paste")
			(net "FM_CPU1_NMI_SYNC_FLOOD_N")
		)
		(pad "2" smd circle
			(at 0.40005 0 90)
			(size 0 0)
			(layers "F.Cu" "F.Mask" "F.Paste")
			(net "CPU1_NMI_SYNC_FLOOD_N")
		)
	)
	(footprint ""
		(layer "F.Cu")
		(at 200.057258 -77.06614 180)
		(property "Reference" "R72"
			(at 0 0 180)
			(layer "F.SilkS")
			(hide yes)
			(effects
				(font
					(size 1.27 1.27)
				)
			)
		)
		(property "Value" ""
			(at 0 0 180)
			(layer "F.Fab")
			(effects
				(font
					(size 1.27 1.27)
				)
			)
		)
		(duplicate_pad_numbers_are_jumpers no)
		(fp_line
			(start 0.7874 0.4064)
			(end -0.7874 0.4064)
			(stroke
				(width 0.1524)
				(type default)
			)
			(layer "F.SilkS")
		)
		(fp_line
			(start 0.7874 -0.4064)
			(end 0.7874 0.4064)
			(stroke
				(width 0.1524)
				(type default)
			)
			(layer "F.SilkS")
		)
		(fp_line
			(start -0.7874 0.4064)
			(end -0.7874 -0.4064)
			(stroke
				(width 0.1524)
				(type default)
			)
			(layer "F.SilkS")
		)
		(fp_line
			(start -0.7874 -0.4064)
			(end 0.7874 -0.4064)
			(stroke
				(width 0.1524)
				(type default)
			)
			(layer "F.SilkS")
		)
		(fp_line
			(start 0.67945 0.3048)
			(end 0.120396 0.3048)
			(stroke
				(width 0.1)
				(type default)
			)
			(layer "F.Fab")
		)
		(fp_line
			(start 0.67945 -0.3048)
			(end 0.67945 0.3048)
			(stroke
				(width 0.1)
				(type default)
			)
			(layer "F.Fab")
		)
		(fp_line
			(start 0.12065 -0.2794)
			(end 0.12065 -0.3048)
			(stroke
				(width 0.1)
				(type default)
			)
			(layer "F.Fab")
		)
		(fp_line
			(start 0.12065 -0.3048)
			(end 0.67945 -0.3048)
			(stroke
				(width 0.1)
				(type default)
			)
			(layer "F.Fab")
		)
		(fp_line
			(start 0.120396 0.3048)
			(end 0.120396 0.2794)
			(stroke
				(width 0.1)
				(type default)
			)
			(layer "F.Fab")
		)
		(fp_line
			(start 0.120396 0.2794)
			(end -0.12065 0.2794)
			(stroke
				(width 0.1)
				(type default)
			)
			(layer "F.Fab")
		)
		(fp_line
			(start -0.12065 0.3048)
			(end -0.67945 0.3048)
			(stroke
				(width 0.1)
				(type default)
			)
			(layer "F.Fab")
		)
		(fp_line
			(start -0.12065 0.2794)
			(end -0.12065 0.3048)
			(stroke
				(width 0.1)
				(type default)
			)
			(layer "F.Fab")
		)
		(fp_line
			(start -0.12065 -0.2794)
			(end 0.12065 -0.2794)
			(stroke
				(width 0.1)
				(type default)
			)
			(layer "F.Fab")
		)
		(fp_line
			(start -0.12065 -0.305054)
			(end -0.12065 -0.2794)
			(stroke
				(width 0.1)
				(type default)
			)
			(layer "F.Fab")
		)
		(fp_line
			(start -0.67945 0.3048)
			(end -0.67945 -0.305054)
			(stroke
				(width 0.1)
				(type default)
			)
			(layer "F.Fab")
		)
		(fp_line
			(start -0.67945 -0.305054)
			(end -0.12065 -0.305054)
			(stroke
				(width 0.1)
				(type default)
			)
			(layer "F.Fab")
		)
		(pad "1" smd circle
			(at -0.40005 0 180)
			(size 0 0)
			(layers "F.Cu" "F.Mask" "F.Paste")
			(net "NCSI_BMC_RXD0_R")
		)
		(pad "2" smd circle
			(at 0.40005 0 180)
			(size 0 0)
			(layers "F.Cu" "F.Mask" "F.Paste")
			(net "RMII_OCP_BMC_RXD_0")
		)
	)
	(footprint ""
		(layer "F.Cu")
		(at 41.5544 -389.0264)
		(property "Reference" "R6721"
			(at 0 0 0)
			(layer "F.SilkS")
			(hide yes)
			(effects
				(font
					(size 1.27 1.27)
				)
			)
		)
		(property "Value" ""
			(at 0 0 0)
			(layer "F.Fab")
			(effects
				(font
					(size 1.27 1.27)
				)
			)
		)
		(duplicate_pad_numbers_are_jumpers no)
		(fp_line
			(start -0.32512 -0.175006)
			(end 0.32512 -0.175006)
			(stroke
				(width 0.1)
				(type default)
			)
			(layer "F.Fab")
		)
		(fp_line
			(start -0.32512 0.175006)
			(end -0.32512 -0.175006)
			(stroke
				(width 0.1)
				(type default)
			)
			(layer "F.Fab")
		)
		(fp_line
			(start 0.32512 -0.175006)
			(end 0.32512 0.175006)
			(stroke
				(width 0.1)
				(type default)
			)
			(layer "F.Fab")
		)
		(fp_line
			(start 0.32512 0.175006)
			(end -0.32512 0.175006)
			(stroke
				(width 0.1)
				(type default)
			)
			(layer "F.Fab")
		)
		(pad "1" smd rect
			(at -0.2667 0)
			(size 0.3048 0.381)
			(layers "F.Cu" "F.Mask" "F.Paste")
			(net "RST_RT_CPU1_P0_RESET_R_N")
		)
		(pad "2" smd rect
			(at 0.2667 0 180)
			(size 0.3048 0.381)
			(layers "F.Cu" "F.Mask" "F.Paste")
			(net "GND")
		)
	)
)
